(kicad_pcb
	(version 20260206)
	(generator "pcbnew")
	(generator_version "10.0")
	(general
		(thickness 1.6)
		(legacy_teardrops no)
	)
	(paper "A4")
	(title_block
		(title "01162023_DA0F0TEBIF0_F0T_Expander_BD_F_brd_V02_OCP.brd")
		(comment 1 "Grand Teton / footprint 6619 of 9728 (PEX0), pads 1305-1420 of 2397")
	)
	(layers
		(0 "F.Cu" signal "TOP")
		(4 "In1.Cu" signal "GND")
		(6 "In2.Cu" signal "VCC")
		(8 "In3.Cu" signal "VCC1")
		(10 "In4.Cu" signal "GND1")
		(12 "In5.Cu" signal "IN1")
		(14 "In6.Cu" signal "GND2")
		(16 "In7.Cu" signal "IN2")
		(18 "In8.Cu" signal "GND3")
		(20 "In9.Cu" signal "IN3")
		(22 "In10.Cu" signal "GND4")
		(24 "In11.Cu" signal "IN4")
		(26 "In12.Cu" signal "GND5")
		(28 "In13.Cu" signal "IN5")
		(30 "In14.Cu" signal "GND6")
		(32 "In15.Cu" signal "IN6")
		(34 "In16.Cu" signal "GND7")
		(2 "B.Cu" signal "BOTTOM")
		(9 "F.Adhes" user "F.Adhesive")
		(11 "B.Adhes" user "B.Adhesive")
		(13 "F.Paste" user "Package Geometry/Pastemask Top")
		(15 "B.Paste" user "Package Geometry/Pastemask Bottom")
		(5 "F.SilkS" user "Ref Des/Silkscreen Top")
		(7 "B.SilkS" user "Ref Des/Silkscreen Bottom")
		(1 "F.Mask" user "Board Geometry/Soldermask Top")
		(3 "B.Mask" user "Board Geometry/Soldermask Bottom")
		(17 "Dwgs.User" user "User.Drawings")
		(19 "Cmts.User" user "User.Comments")
		(21 "Eco1.User" user "User.Eco1")
		(23 "Eco2.User" user "User.Eco2")
		(25 "Edge.Cuts" user "Board Geometry/Outline")
		(27 "Margin" user)
		(31 "F.CrtYd" user "Package Geometry/Place Bound Top")
		(29 "B.CrtYd" user "Package Geometry/Place Bound Bottom")
		(35 "F.Fab" user "Ref Des/Assembly Top")
		(33 "B.Fab" user "Ref Des/Assembly Bottom")
	)
	(footprint ""
		(layer "F.Cu")
		(at 59.649868 -295.89984)
		(property "Reference" "PEX0"
			(at -3.360166 35.566858 0)
			(unlocked yes)
			(layer "F.SilkS")
			(effects
				(font
					(size 2.032 1.524)
					(thickness 0.1524)
				)
				(justify left)
			)
		)
		(property "Value" ""
			(at 0 0 0)
			(layer "F.Fab")
			(effects
				(font
					(size 1.27 1.27)
				)
			)
		)
		(duplicate_pad_numbers_are_jumpers no)
		(pad "BE33" smd circle
			(at 7.599934 18.999962)
			(size 0.4572 0.4572)
			(layers "F.Cu" "F.Mask" "F.Paste")
			(net "GND")
		)
		(pad "BE34" smd circle
			(at 8.549894 18.999962)
			(size 0.4572 0.4572)
			(layers "F.Cu" "F.Mask" "F.Paste")
			(net "GND")
		)
		(pad "BE35" smd circle
			(at 9.500108 18.999962)
			(size 0.4572 0.4572)
			(layers "F.Cu" "F.Mask" "F.Paste")
			(net "GND")
		)
		(pad "BE36" smd circle
			(at 10.450068 18.999962)
			(size 0.4572 0.4572)
			(layers "F.Cu" "F.Mask" "F.Paste")
			(net "GND")
		)
		(pad "BE37" smd circle
			(at 11.400028 18.999962)
			(size 0.4572 0.4572)
			(layers "F.Cu" "F.Mask" "F.Paste")
			(net "GND")
		)
		(pad "BE38" smd circle
			(at 12.349988 18.999962)
			(size 0.4572 0.4572)
			(layers "F.Cu" "F.Mask" "F.Paste")
			(net "GND")
		)
		(pad "BE39" smd circle
			(at 13.299948 18.999962)
			(size 0.4572 0.4572)
			(layers "F.Cu" "F.Mask" "F.Paste")
			(net "GND")
		)
		(pad "BE40" smd circle
			(at 14.249908 18.999962)
			(size 0.4572 0.4572)
			(layers "F.Cu" "F.Mask" "F.Paste")
			(net "GND")
		)
		(pad "BE41" smd circle
			(at 15.200122 18.999962)
			(size 0.4572 0.4572)
			(layers "F.Cu" "F.Mask" "F.Paste")
			(net "GND")
		)
		(pad "BE42" smd circle
			(at 16.150082 18.999962)
			(size 0.4572 0.4572)
			(layers "F.Cu" "F.Mask" "F.Paste")
			(net "GND")
		)
		(pad "BE43" smd circle
			(at 17.100042 18.999962)
			(size 0.4572 0.4572)
			(layers "F.Cu" "F.Mask" "F.Paste")
			(net "GND")
		)
		(pad "BE44" smd circle
			(at 18.050002 18.999962)
			(size 0.4572 0.4572)
			(layers "F.Cu" "F.Mask" "F.Paste")
			(net "GND")
		)
		(pad "BE45" smd circle
			(at 18.999962 18.999962)
			(size 0.4572 0.4572)
			(layers "F.Cu" "F.Mask" "F.Paste")
			(net "GND")
		)
		(pad "BE46" smd circle
			(at 19.949922 18.999962)
			(size 0.4572 0.4572)
			(layers "F.Cu" "F.Mask" "F.Paste")
			(net "GND")
		)
		(pad "BE47" smd circle
			(at 20.899882 18.999962)
			(size 0.4572 0.4572)
			(layers "F.Cu" "F.Mask" "F.Paste")
			(net "GND")
		)
		(pad "BE48" smd circle
			(at 21.850096 18.999962)
			(size 0.4572 0.4572)
			(layers "F.Cu" "F.Mask" "F.Paste")
			(net "P5E_PEX0_STN0_TX_DP<8>")
		)
		(pad "BE49" smd circle
			(at 22.800056 18.999962)
			(size 0.4572 0.4572)
			(layers "F.Cu" "F.Mask" "F.Paste")
			(net "P5E_PEX0_STN0_TX_DN<8>")
		)
		(pad "BF1" smd circle
			(at -22.800056 19.949922)
			(size 0.4572 0.4572)
			(layers "F.Cu" "F.Mask" "F.Paste")
			(net "GND")
		)
		(pad "BF2" smd circle
			(at -21.850096 19.949922)
			(size 0.4572 0.4572)
			(layers "F.Cu" "F.Mask" "F.Paste")
			(net "GND")
		)
		(pad "BF3" smd circle
			(at -20.899882 19.949922)
			(size 0.4572 0.4572)
			(layers "F.Cu" "F.Mask" "F.Paste")
			(net "GND")
		)
		(pad "BF4" smd circle
			(at -19.949922 19.949922)
			(size 0.4572 0.4572)
			(layers "F.Cu" "F.Mask" "F.Paste")
			(net "Net_2733")
		)
		(pad "BF5" smd circle
			(at -18.999962 19.949922)
			(size 0.4572 0.4572)
			(layers "F.Cu" "F.Mask" "F.Paste")
			(net "GND")
		)
		(pad "BF6" smd circle
			(at -18.050002 19.949922)
			(size 0.4572 0.4572)
			(layers "F.Cu" "F.Mask" "F.Paste")
			(net "Net_2735")
		)
		(pad "BF7" smd circle
			(at -17.100042 19.949922)
			(size 0.4572 0.4572)
			(layers "F.Cu" "F.Mask" "F.Paste")
			(net "GND")
		)
		(pad "BF8" smd circle
			(at -16.150082 19.949922)
			(size 0.4572 0.4572)
			(layers "F.Cu" "F.Mask" "F.Paste")
			(net "Net_2737")
		)
		(pad "BF9" smd circle
			(at -15.200122 19.949922)
			(size 0.4572 0.4572)
			(layers "F.Cu" "F.Mask" "F.Paste")
			(net "GND")
		)
		(pad "BF10" smd circle
			(at -14.249908 19.949922)
			(size 0.4572 0.4572)
			(layers "F.Cu" "F.Mask" "F.Paste")
			(net "P5E_PEX0_STN2_RX_DP<46>")
		)
		(pad "BF11" smd circle
			(at -13.299948 19.949922)
			(size 0.4572 0.4572)
			(layers "F.Cu" "F.Mask" "F.Paste")
			(net "GND")
		)
		(pad "BF12" smd circle
			(at -12.349988 19.949922)
			(size 0.4572 0.4572)
			(layers "F.Cu" "F.Mask" "F.Paste")
			(net "P5E_PEX0_STN2_RX_DP<44>")
		)
		(pad "BF13" smd circle
			(at -11.400028 19.949922)
			(size 0.4572 0.4572)
			(layers "F.Cu" "F.Mask" "F.Paste")
			(net "GND")
		)
		(pad "BF14" smd circle
			(at -10.450068 19.949922)
			(size 0.4572 0.4572)
			(layers "F.Cu" "F.Mask" "F.Paste")
			(net "P5E_PEX0_STN2_RX_DP<42>")
		)
		(pad "BF15" smd circle
			(at -9.500108 19.949922)
			(size 0.4572 0.4572)
			(layers "F.Cu" "F.Mask" "F.Paste")
			(net "GND")
		)
		(pad "BF16" smd circle
			(at -8.549894 19.949922)
			(size 0.4572 0.4572)
			(layers "F.Cu" "F.Mask" "F.Paste")
			(net "P5E_PEX0_STN2_RX_DP<40>")
		)
		(pad "BF17" smd circle
			(at -7.599934 19.949922)
			(size 0.4572 0.4572)
			(layers "F.Cu" "F.Mask" "F.Paste")
			(net "GND")
		)
		(pad "BF18" smd circle
			(at -6.649974 19.949922)
			(size 0.4572 0.4572)
			(layers "F.Cu" "F.Mask" "F.Paste")
			(net "P5E_PEX0_STN2_RX_DP<38>")
		)
		(pad "BF19" smd circle
			(at -5.700014 19.949922)
			(size 0.4572 0.4572)
			(layers "F.Cu" "F.Mask" "F.Paste")
			(net "GND")
		)
		(pad "BF20" smd circle
			(at -4.750054 19.949922)
			(size 0.4572 0.4572)
			(layers "F.Cu" "F.Mask" "F.Paste")
			(net "P5E_PEX0_STN2_RX_DP<36>")
		)
		(pad "BF21" smd circle
			(at -3.800094 19.949922)
			(size 0.4572 0.4572)
			(layers "F.Cu" "F.Mask" "F.Paste")
			(net "GND")
		)
		(pad "BF22" smd circle
			(at -2.84988 19.949922)
			(size 0.4572 0.4572)
			(layers "F.Cu" "F.Mask" "F.Paste")
			(net "P5E_PEX0_STN2_RX_DP<34>")
		)
		(pad "BF23" smd circle
			(at -1.89992 19.949922)
			(size 0.4572 0.4572)
			(layers "F.Cu" "F.Mask" "F.Paste")
			(net "GND")
		)
		(pad "BF24" smd circle
			(at -0.94996 19.949922)
			(size 0.4572 0.4572)
			(layers "F.Cu" "F.Mask" "F.Paste")
			(net "P5E_PEX0_STN2_RX_DP<32>")
		)
		(pad "BF25" smd circle
			(at 0 19.949922)
			(size 0.4572 0.4572)
			(layers "F.Cu" "F.Mask" "F.Paste")
			(net "GND")
		)
		(pad "BF26" smd circle
			(at 0.94996 19.949922)
			(size 0.4572 0.4572)
			(layers "F.Cu" "F.Mask" "F.Paste")
			(net "P5E_PEX0_STN1_RX_DP<17>")
		)
		(pad "BF27" smd circle
			(at 1.89992 19.949922)
			(size 0.4572 0.4572)
			(layers "F.Cu" "F.Mask" "F.Paste")
			(net "GND")
		)
		(pad "BF28" smd circle
			(at 2.84988 19.949922)
			(size 0.4572 0.4572)
			(layers "F.Cu" "F.Mask" "F.Paste")
			(net "P5E_PEX0_STN1_RX_DP<19>")
		)
		(pad "BF29" smd circle
			(at 3.800094 19.949922)
			(size 0.4572 0.4572)
			(layers "F.Cu" "F.Mask" "F.Paste")
			(net "GND")
		)
		(pad "BF30" smd circle
			(at 4.750054 19.949922)
			(size 0.4572 0.4572)
			(layers "F.Cu" "F.Mask" "F.Paste")
			(net "P5E_PEX0_STN1_RX_DP<21>")
		)
		(pad "BF31" smd circle
			(at 5.700014 19.949922)
			(size 0.4572 0.4572)
			(layers "F.Cu" "F.Mask" "F.Paste")
			(net "GND")
		)
		(pad "BF32" smd circle
			(at 6.649974 19.949922)
			(size 0.4572 0.4572)
			(layers "F.Cu" "F.Mask" "F.Paste")
			(net "P5E_PEX0_STN1_RX_DP<23>")
		)
		(pad "BF33" smd circle
			(at 7.599934 19.949922)
			(size 0.4572 0.4572)
			(layers "F.Cu" "F.Mask" "F.Paste")
			(net "GND")
		)
		(pad "BF34" smd circle
			(at 8.549894 19.949922)
			(size 0.4572 0.4572)
			(layers "F.Cu" "F.Mask" "F.Paste")
			(net "P5E_PEX0_STN1_RX_DP<25>")
		)
		(pad "BF35" smd circle
			(at 9.500108 19.949922)
			(size 0.4572 0.4572)
			(layers "F.Cu" "F.Mask" "F.Paste")
			(net "GND")
		)
		(pad "BF36" smd circle
			(at 10.450068 19.949922)
			(size 0.4572 0.4572)
			(layers "F.Cu" "F.Mask" "F.Paste")
			(net "P5E_PEX0_STN1_RX_DP<27>")
		)
		(pad "BF37" smd circle
			(at 11.400028 19.949922)
			(size 0.4572 0.4572)
			(layers "F.Cu" "F.Mask" "F.Paste")
			(net "GND")
		)
		(pad "BF38" smd circle
			(at 12.349988 19.949922)
			(size 0.4572 0.4572)
			(layers "F.Cu" "F.Mask" "F.Paste")
			(net "P5E_PEX0_STN1_RX_DP<29>")
		)
		(pad "BF39" smd circle
			(at 13.299948 19.949922)
			(size 0.4572 0.4572)
			(layers "F.Cu" "F.Mask" "F.Paste")
			(net "GND")
		)
		(pad "BF40" smd circle
			(at 14.249908 19.949922)
			(size 0.4572 0.4572)
			(layers "F.Cu" "F.Mask" "F.Paste")
			(net "P5E_PEX0_STN1_RX_DP<31>")
		)
		(pad "BF41" smd circle
			(at 15.200122 19.949922)
			(size 0.4572 0.4572)
			(layers "F.Cu" "F.Mask" "F.Paste")
			(net "GND")
		)
		(pad "BF42" smd circle
			(at 16.150082 19.949922)
			(size 0.4572 0.4572)
			(layers "F.Cu" "F.Mask" "F.Paste")
			(net "P5E_PEX0_STN0_RX_DP<14>")
		)
		(pad "BF43" smd circle
			(at 17.100042 19.949922)
			(size 0.4572 0.4572)
			(layers "F.Cu" "F.Mask" "F.Paste")
			(net "GND")
		)
		(pad "BF44" smd circle
			(at 18.050002 19.949922)
			(size 0.4572 0.4572)
			(layers "F.Cu" "F.Mask" "F.Paste")
			(net "P5E_PEX0_STN0_RX_DP<12>")
		)
		(pad "BF45" smd circle
			(at 18.999962 19.949922)
			(size 0.4572 0.4572)
			(layers "F.Cu" "F.Mask" "F.Paste")
			(net "GND")
		)
		(pad "BF46" smd circle
			(at 19.949922 19.949922)
			(size 0.4572 0.4572)
			(layers "F.Cu" "F.Mask" "F.Paste")
			(net "P5E_PEX0_STN0_RX_DP<10>")
		)
		(pad "BF47" smd circle
			(at 20.899882 19.949922)
			(size 0.4572 0.4572)
			(layers "F.Cu" "F.Mask" "F.Paste")
			(net "GND")
		)
		(pad "BF48" smd circle
			(at 21.850096 19.949922)
			(size 0.4572 0.4572)
			(layers "F.Cu" "F.Mask" "F.Paste")
			(net "GND")
		)
		(pad "BF49" smd circle
			(at 22.800056 19.949922)
			(size 0.4572 0.4572)
			(layers "F.Cu" "F.Mask" "F.Paste")
			(net "GND")
		)
		(pad "BG1" smd circle
			(at -22.800056 20.899882)
			(size 0.4572 0.4572)
			(layers "F.Cu" "F.Mask" "F.Paste")
			(net "Net_2717")
		)
		(pad "BG2" smd circle
			(at -21.850096 20.899882)
			(size 0.4572 0.4572)
			(layers "F.Cu" "F.Mask" "F.Paste")
			(net "Net_2731")
		)
		(pad "BG3" smd circle
			(at -20.899882 20.899882)
			(size 0.4572 0.4572)
			(layers "F.Cu" "F.Mask" "F.Paste")
			(net "GND")
		)
		(pad "BG4" smd circle
			(at -19.949922 20.899882)
			(size 0.4572 0.4572)
			(layers "F.Cu" "F.Mask" "F.Paste")
			(net "Net_2719")
		)
		(pad "BG5" smd circle
			(at -18.999962 20.899882)
			(size 0.4572 0.4572)
			(layers "F.Cu" "F.Mask" "F.Paste")
			(net "GND")
		)
		(pad "BG6" smd circle
			(at -18.050002 20.899882)
			(size 0.4572 0.4572)
			(layers "F.Cu" "F.Mask" "F.Paste")
			(net "Net_2721")
		)
		(pad "BG7" smd circle
			(at -17.100042 20.899882)
			(size 0.4572 0.4572)
			(layers "F.Cu" "F.Mask" "F.Paste")
			(net "GND")
		)
		(pad "BG8" smd circle
			(at -16.150082 20.899882)
			(size 0.4572 0.4572)
			(layers "F.Cu" "F.Mask" "F.Paste")
			(net "Net_2723")
		)
		(pad "BG9" smd circle
			(at -15.200122 20.899882)
			(size 0.4572 0.4572)
			(layers "F.Cu" "F.Mask" "F.Paste")
			(net "GND")
		)
		(pad "BG10" smd circle
			(at -14.249908 20.899882)
			(size 0.4572 0.4572)
			(layers "F.Cu" "F.Mask" "F.Paste")
			(net "P5E_PEX0_STN2_RX_DN<46>")
		)
		(pad "BG11" smd circle
			(at -13.299948 20.899882)
			(size 0.4572 0.4572)
			(layers "F.Cu" "F.Mask" "F.Paste")
			(net "GND")
		)
		(pad "BG12" smd circle
			(at -12.349988 20.899882)
			(size 0.4572 0.4572)
			(layers "F.Cu" "F.Mask" "F.Paste")
			(net "P5E_PEX0_STN2_RX_DN<44>")
		)
		(pad "BG13" smd circle
			(at -11.400028 20.899882)
			(size 0.4572 0.4572)
			(layers "F.Cu" "F.Mask" "F.Paste")
			(net "GND")
		)
		(pad "BG14" smd circle
			(at -10.450068 20.899882)
			(size 0.4572 0.4572)
			(layers "F.Cu" "F.Mask" "F.Paste")
			(net "P5E_PEX0_STN2_RX_DN<42>")
		)
		(pad "BG15" smd circle
			(at -9.500108 20.899882)
			(size 0.4572 0.4572)
			(layers "F.Cu" "F.Mask" "F.Paste")
			(net "GND")
		)
		(pad "BG16" smd circle
			(at -8.549894 20.899882)
			(size 0.4572 0.4572)
			(layers "F.Cu" "F.Mask" "F.Paste")
			(net "P5E_PEX0_STN2_RX_DN<40>")
		)
		(pad "BG17" smd circle
			(at -7.599934 20.899882)
			(size 0.4572 0.4572)
			(layers "F.Cu" "F.Mask" "F.Paste")
			(net "GND")
		)
		(pad "BG18" smd circle
			(at -6.649974 20.899882)
			(size 0.4572 0.4572)
			(layers "F.Cu" "F.Mask" "F.Paste")
			(net "P5E_PEX0_STN2_RX_DN<38>")
		)
		(pad "BG19" smd circle
			(at -5.700014 20.899882)
			(size 0.4572 0.4572)
			(layers "F.Cu" "F.Mask" "F.Paste")
			(net "GND")
		)
		(pad "BG20" smd circle
			(at -4.750054 20.899882)
			(size 0.4572 0.4572)
			(layers "F.Cu" "F.Mask" "F.Paste")
			(net "P5E_PEX0_STN2_RX_DN<36>")
		)
		(pad "BG21" smd circle
			(at -3.800094 20.899882)
			(size 0.4572 0.4572)
			(layers "F.Cu" "F.Mask" "F.Paste")
			(net "GND")
		)
		(pad "BG22" smd circle
			(at -2.84988 20.899882)
			(size 0.4572 0.4572)
			(layers "F.Cu" "F.Mask" "F.Paste")
			(net "P5E_PEX0_STN2_RX_DN<34>")
		)
		(pad "BG23" smd circle
			(at -1.89992 20.899882)
			(size 0.4572 0.4572)
			(layers "F.Cu" "F.Mask" "F.Paste")
			(net "GND")
		)
		(pad "BG24" smd circle
			(at -0.94996 20.899882)
			(size 0.4572 0.4572)
			(layers "F.Cu" "F.Mask" "F.Paste")
			(net "P5E_PEX0_STN2_RX_DN<32>")
		)
		(pad "BG25" smd circle
			(at 0 20.899882)
			(size 0.4572 0.4572)
			(layers "F.Cu" "F.Mask" "F.Paste")
			(net "GND")
		)
		(pad "BG26" smd circle
			(at 0.94996 20.899882)
			(size 0.4572 0.4572)
			(layers "F.Cu" "F.Mask" "F.Paste")
			(net "P5E_PEX0_STN1_RX_DN<17>")
		)
		(pad "BG27" smd circle
			(at 1.89992 20.899882)
			(size 0.4572 0.4572)
			(layers "F.Cu" "F.Mask" "F.Paste")
			(net "GND")
		)
		(pad "BG28" smd circle
			(at 2.84988 20.899882)
			(size 0.4572 0.4572)
			(layers "F.Cu" "F.Mask" "F.Paste")
			(net "P5E_PEX0_STN1_RX_DN<19>")
		)
		(pad "BG29" smd circle
			(at 3.800094 20.899882)
			(size 0.4572 0.4572)
			(layers "F.Cu" "F.Mask" "F.Paste")
			(net "GND")
		)
		(pad "BG30" smd circle
			(at 4.750054 20.899882)
			(size 0.4572 0.4572)
			(layers "F.Cu" "F.Mask" "F.Paste")
			(net "P5E_PEX0_STN1_RX_DN<21>")
		)
		(pad "BG31" smd circle
			(at 5.700014 20.899882)
			(size 0.4572 0.4572)
			(layers "F.Cu" "F.Mask" "F.Paste")
			(net "GND")
		)
		(pad "BG32" smd circle
			(at 6.649974 20.899882)
			(size 0.4572 0.4572)
			(layers "F.Cu" "F.Mask" "F.Paste")
			(net "P5E_PEX0_STN1_RX_DN<23>")
		)
		(pad "BG33" smd circle
			(at 7.599934 20.899882)
			(size 0.4572 0.4572)
			(layers "F.Cu" "F.Mask" "F.Paste")
			(net "GND")
		)
		(pad "BG34" smd circle
			(at 8.549894 20.899882)
			(size 0.4572 0.4572)
			(layers "F.Cu" "F.Mask" "F.Paste")
			(net "P5E_PEX0_STN1_RX_DN<25>")
		)
		(pad "BG35" smd circle
			(at 9.500108 20.899882)
			(size 0.4572 0.4572)
			(layers "F.Cu" "F.Mask" "F.Paste")
			(net "GND")
		)
		(pad "BG36" smd circle
			(at 10.450068 20.899882)
			(size 0.4572 0.4572)
			(layers "F.Cu" "F.Mask" "F.Paste")
			(net "P5E_PEX0_STN1_RX_DN<27>")
		)
		(pad "BG37" smd circle
			(at 11.400028 20.899882)
			(size 0.4572 0.4572)
			(layers "F.Cu" "F.Mask" "F.Paste")
			(net "GND")
		)
		(pad "BG38" smd circle
			(at 12.349988 20.899882)
			(size 0.4572 0.4572)
			(layers "F.Cu" "F.Mask" "F.Paste")
			(net "P5E_PEX0_STN1_RX_DN<29>")
		)
		(pad "BG39" smd circle
			(at 13.299948 20.899882)
			(size 0.4572 0.4572)
			(layers "F.Cu" "F.Mask" "F.Paste")
			(net "GND")
		)
		(pad "BG40" smd circle
			(at 14.249908 20.899882)
			(size 0.4572 0.4572)
			(layers "F.Cu" "F.Mask" "F.Paste")
			(net "P5E_PEX0_STN1_RX_DN<31>")
		)
		(pad "BG41" smd circle
			(at 15.200122 20.899882)
			(size 0.4572 0.4572)
			(layers "F.Cu" "F.Mask" "F.Paste")
			(net "GND")
		)
		(pad "BG42" smd circle
			(at 16.150082 20.899882)
			(size 0.4572 0.4572)
			(layers "F.Cu" "F.Mask" "F.Paste")
			(net "P5E_PEX0_STN0_RX_DN<14>")
		)
		(pad "BG43" smd circle
			(at 17.100042 20.899882)
			(size 0.4572 0.4572)
			(layers "F.Cu" "F.Mask" "F.Paste")
			(net "GND")
		)
		(pad "BG44" smd circle
			(at 18.050002 20.899882)
			(size 0.4572 0.4572)
			(layers "F.Cu" "F.Mask" "F.Paste")
			(net "P5E_PEX0_STN0_RX_DN<12>")
		)
		(pad "BG45" smd circle
			(at 18.999962 20.899882)
			(size 0.4572 0.4572)
			(layers "F.Cu" "F.Mask" "F.Paste")
			(net "GND")
		)
		(pad "BG46" smd circle
			(at 19.949922 20.899882)
			(size 0.4572 0.4572)
			(layers "F.Cu" "F.Mask" "F.Paste")
			(net "P5E_PEX0_STN0_RX_DN<10>")
		)
		(pad "BG47" smd circle
			(at 20.899882 20.899882)
			(size 0.4572 0.4572)
			(layers "F.Cu" "F.Mask" "F.Paste")
			(net "GND")
		)
		(pad "BG48" smd circle
			(at 21.850096 20.899882)
			(size 0.4572 0.4572)
			(layers "F.Cu" "F.Mask" "F.Paste")
			(net "P5E_PEX0_STN0_RX_DP<8>")
		)
		(pad "BG49" smd circle
			(at 22.800056 20.899882)
			(size 0.4572 0.4572)
			(layers "F.Cu" "F.Mask" "F.Paste")
			(net "P5E_PEX0_STN0_RX_DN<8>")
		)
		(pad "BH1" smd circle
			(at -22.800056 21.850096)
			(size 0.4572 0.4572)
			(layers "F.Cu" "F.Mask" "F.Paste")
			(net "GND")
		)
	)
)
